# S9S_MB_2U (Grand Teton) — schematic netlist excerpt (pin names and nets, part order shuffled) for the footprints in the layout excerpt that follows; sources: Cadence DE-HDL packaged netlist, KiCad conversion of 03242023_DA0F0TMBIJ0_F0T_Motherboard_J_brd_V01_OCP.brd

R4764  Q_RES  10K 1% CHIP  pkg 0402LF  page 158 : A = P3V3_AUX ; B = HP_OCP_V3_1_EN
R4398  Q_RES  1.5K 1% CHIP  pkg 0402LF  page 121 : A = H_CPU1_THERMTRIP_N ; B = H_CPU1_THERMTRIP_R_N

(kicad_pcb
	(version 20260206)
	(generator "pcbnew")
	(generator_version "10.0")
	(general
		(thickness 1.6)
		(legacy_teardrops no)
	)
	(paper "A4")
	(title_block
		(title "03242023_DA0F0TMBIJ0_F0T_Motherboard_J_brd_V01_OCP.brd")
		(comment 1 "Grand Teton / footprints 170-171 of 6105")
	)
	(layers
		(0 "F.Cu" signal "TOP")
		(4 "In1.Cu" signal "GND")
		(6 "In2.Cu" signal "IN1")
		(8 "In3.Cu" signal "GND1")
		(10 "In4.Cu" signal "IN2")
		(12 "In5.Cu" signal "GND2")
		(14 "In6.Cu" signal "IN3")
		(16 "In7.Cu" signal "GND3")
		(18 "In8.Cu" signal "VCC")
		(20 "In9.Cu" signal "VCC1")
		(22 "In10.Cu" signal "GND4")
		(24 "In11.Cu" signal "IN4")
		(26 "In12.Cu" signal "GND5")
		(28 "In13.Cu" signal "IN5")
		(30 "In14.Cu" signal "GND6")
		(32 "In15.Cu" signal "IN6")
		(34 "In16.Cu" signal "GND7")
		(2 "B.Cu" signal "BOTTOM")
		(9 "F.Adhes" user "F.Adhesive")
		(11 "B.Adhes" user "B.Adhesive")
		(13 "F.Paste" user "Package Geometry/Pastemask Top")
		(15 "B.Paste" user "Package Geometry/Pastemask Bottom")
		(5 "F.SilkS" user "Ref Des/Silkscreen Top")
		(7 "B.SilkS" user "Ref Des/Silkscreen Bottom")
		(1 "F.Mask" user "Board Geometry/Soldermask Top")
		(3 "B.Mask" user "Board Geometry/Soldermask Bottom")
		(17 "Dwgs.User" user "User.Drawings")
		(19 "Cmts.User" user "User.Comments")
		(21 "Eco1.User" user "User.Eco1")
		(23 "Eco2.User" user "User.Eco2")
		(25 "Edge.Cuts" user "Board Geometry/Outline")
		(27 "Margin" user)
		(31 "F.CrtYd" user "Package Geometry/Place Bound Top")
		(29 "B.CrtYd" user "Package Geometry/Place Bound Bottom")
		(35 "F.Fab" user "Ref Des/Assembly Top")
		(33 "B.Fab" user "Ref Des/Assembly Bottom")
	)
	(footprint ""
		(layer "F.Cu")
		(at 125.65888 -99.405948)
		(property "Reference" "R4398"
			(at 0 0 0)
			(layer "F.SilkS")
			(hide yes)
			(effects
				(font
					(size 1.27 1.27)
				)
			)
		)
		(property "Value" ""
			(at 0 0 0)
			(layer "F.Fab")
			(effects
				(font
					(size 1.27 1.27)
				)
			)
		)
		(duplicate_pad_numbers_are_jumpers no)
		(fp_line
			(start -0.7874 -0.4064)
			(end 0.7874 -0.4064)
			(stroke
				(width 0.1524)
				(type default)
			)
			(layer "F.SilkS")
		)
		(fp_line
			(start -0.7874 0.4064)
			(end -0.7874 -0.4064)
			(stroke
				(width 0.1524)
				(type default)
			)
			(layer "F.SilkS")
		)
		(fp_line
			(start 0.7874 -0.4064)
			(end 0.7874 0.4064)
			(stroke
				(width 0.1524)
				(type default)
			)
			(layer "F.SilkS")
		)
		(fp_line
			(start 0.7874 0.4064)
			(end -0.7874 0.4064)
			(stroke
				(width 0.1524)
				(type default)
			)
			(layer "F.SilkS")
		)
		(fp_line
			(start -0.67945 -0.305054)
			(end -0.12065 -0.305054)
			(stroke
				(width 0.1)
				(type default)
			)
			(layer "F.Fab")
		)
		(fp_line
			(start -0.67945 0.3048)
			(end -0.67945 -0.305054)
			(stroke
				(width 0.1)
				(type default)
			)
			(layer "F.Fab")
		)
		(fp_line
			(start -0.12065 -0.305054)
			(end -0.12065 -0.2794)
			(stroke
				(width 0.1)
				(type default)
			)
			(layer "F.Fab")
		)
		(fp_line
			(start -0.12065 -0.2794)
			(end 0.12065 -0.2794)
			(stroke
				(width 0.1)
				(type default)
			)
			(layer "F.Fab")
		)
		(fp_line
			(start -0.12065 0.2794)
			(end -0.12065 0.3048)
			(stroke
				(width 0.1)
				(type default)
			)
			(layer "F.Fab")
		)
		(fp_line
			(start -0.12065 0.3048)
			(end -0.67945 0.3048)
			(stroke
				(width 0.1)
				(type default)
			)
			(layer "F.Fab")
		)
		(fp_line
			(start 0.120396 0.2794)
			(end -0.12065 0.2794)
			(stroke
				(width 0.1)
				(type default)
			)
			(layer "F.Fab")
		)
		(fp_line
			(start 0.120396 0.3048)
			(end 0.120396 0.2794)
			(stroke
				(width 0.1)
				(type default)
			)
			(layer "F.Fab")
		)
		(fp_line
			(start 0.12065 -0.3048)
			(end 0.67945 -0.3048)
			(stroke
				(width 0.1)
				(type default)
			)
			(layer "F.Fab")
		)
		(fp_line
			(start 0.12065 -0.2794)
			(end 0.12065 -0.3048)
			(stroke
				(width 0.1)
				(type default)
			)
			(layer "F.Fab")
		)
		(fp_line
			(start 0.67945 -0.3048)
			(end 0.67945 0.3048)
			(stroke
				(width 0.1)
				(type default)
			)
			(layer "F.Fab")
		)
		(fp_line
			(start 0.67945 0.3048)
			(end 0.120396 0.3048)
			(stroke
				(width 0.1)
				(type default)
			)
			(layer "F.Fab")
		)
		(pad "1" smd circle
			(at -0.40005 0)
			(size 0 0)
			(layers "F.Cu" "F.Mask" "F.Paste")
			(net "H_CPU1_THERMTRIP_N")
		)
		(pad "2" smd circle
			(at 0.40005 0)
			(size 0 0)
			(layers "F.Cu" "F.Mask" "F.Paste")
			(net "H_CPU1_THERMTRIP_R_N")
		)
	)
	(footprint ""
		(layer "F.Cu")
		(at 451.81774 -115.22456 90)
		(property "Reference" "R4764"
			(at 0 0 90)
			(layer "F.SilkS")
			(hide yes)
			(effects
				(font
					(size 1.27 1.27)
				)
			)
		)
		(property "Value" ""
			(at 0 0 90)
			(layer "F.Fab")
			(effects
				(font
					(size 1.27 1.27)
				)
			)
		)
		(duplicate_pad_numbers_are_jumpers no)
		(fp_line
			(start 0.7874 -0.4064)
			(end 0.7874 0.4064)
			(stroke
				(width 0.1524)
				(type default)
			)
			(layer "F.SilkS")
		)
		(fp_line
			(start -0.7874 -0.4064)
			(end 0.7874 -0.4064)
			(stroke
				(width 0.1524)
				(type default)
			)
			(layer "F.SilkS")
		)
		(fp_line
			(start 0.7874 0.4064)
			(end -0.7874 0.4064)
			(stroke
				(width 0.1524)
				(type default)
			)
			(layer "F.SilkS")
		)
		(fp_line
			(start -0.7874 0.4064)
			(end -0.7874 -0.4064)
			(stroke
				(width 0.1524)
				(type default)
			)
			(layer "F.SilkS")
		)
		(fp_line
			(start -0.12065 -0.305054)
			(end -0.12065 -0.2794)
			(stroke
				(width 0.1)
				(type default)
			)
			(layer "F.Fab")
		)
		(fp_line
			(start -0.67945 -0.305054)
			(end -0.12065 -0.305054)
			(stroke
				(width 0.1)
				(type default)
			)
			(layer "F.Fab")
		)
		(fp_line
			(start 0.67945 -0.3048)
			(end 0.67945 0.3048)
			(stroke
				(width 0.1)
				(type default)
			)
			(layer "F.Fab")
		)
		(fp_line
			(start 0.12065 -0.3048)
			(end 0.67945 -0.3048)
			(stroke
				(width 0.1)
				(type default)
			)
			(layer "F.Fab")
		)
		(fp_line
			(start 0.12065 -0.2794)
			(end 0.12065 -0.3048)
			(stroke
				(width 0.1)
				(type default)
			)
			(layer "F.Fab")
		)
		(fp_line
			(start -0.12065 -0.2794)
			(end 0.12065 -0.2794)
			(stroke
				(width 0.1)
				(type default)
			)
			(layer "F.Fab")
		)
		(fp_line
			(start 0.120396 0.2794)
			(end -0.12065 0.2794)
			(stroke
				(width 0.1)
				(type default)
			)
			(layer "F.Fab")
		)
		(fp_line
			(start -0.12065 0.2794)
			(end -0.12065 0.3048)
			(stroke
				(width 0.1)
				(type default)
			)
			(layer "F.Fab")
		)
		(fp_line
			(start 0.67945 0.3048)
			(end 0.120396 0.3048)
			(stroke
				(width 0.1)
				(type default)
			)
			(layer "F.Fab")
		)
		(fp_line
			(start 0.120396 0.3048)
			(end 0.120396 0.2794)
			(stroke
				(width 0.1)
				(type default)
			)
			(layer "F.Fab")
		)
		(fp_line
			(start -0.12065 0.3048)
			(end -0.67945 0.3048)
			(stroke
				(width 0.1)
				(type default)
			)
			(layer "F.Fab")
		)
		(fp_line
			(start -0.67945 0.3048)
			(end -0.67945 -0.305054)
			(stroke
				(width 0.1)
				(type default)
			)
			(layer "F.Fab")
		)
		(pad "1" smd circle
			(at -0.40005 0 90)
			(size 0 0)
			(layers "F.Cu" "F.Mask" "F.Paste")
			(net "P3V3_AUX")
		)
		(pad "2" smd circle
			(at 0.40005 0 90)
			(size 0 0)
			(layers "F.Cu" "F.Mask" "F.Paste")
			(net "HP_OCP_V3_1_EN")
		)
	)
)
